FILE_TYPE = MACRO_DRAWING;
SET COLOR_WIRE YELLOW;
SET COLOR_PROP ORANGE;
SET COLOR_DOT WHITE;
SET COLOR_ARC YELLOW;
SET COLOR_BODY GREEN;
SET COLOR_NOTE PURPLE;
SET PROP_DISPLAY VALUE;
SET PAGE_NUMBER P19;
FORCEADD SOCKET4677_AZIF0045P001C01CS..7
(1500 2625);
FORCEPROP 1 LAST PART_NUMBER DGA^7000023
J 0
(450 3975);
DISPLAY 0.723404 (450 3975);
PAINT GREEN (450 3975);
DISPLAY INVISIBLE (450 3975);
FORCEPROP 2 LAST PART_TYPE SMLF
J 0
(450 4150);
DISPLAY 1.021277 (450 4150);
FORCEPROP 1 LAST MATERIAL IO
J 0
(450 3900);
DISPLAY 0.723404 (450 3900);
PAINT GREEN (450 3900);
FORCEPROP 2 LAST VALUE SOCKET4677_AZIF0045-P001C01CS
J 0
(450 4100);
DISPLAY 1.021277 (450 4100);
FORCEPROP 1 LAST $LOCATION U2
J 0
(450 4050);
DISPLAY 0.723404 (450 4050);
PAINT GREEN (450 4050);
FORCEPROP 0 LASTPIN (300 2400) $PN CC29
J 2
(290 2410);
DISPLAY 0.680851 (290 2410);
PAINT MONO (290 2410);
FORCEPROP 0 LASTPIN (300 1600) $PN CB30
J 2
(290 1610);
DISPLAY 0.680851 (290 1610);
PAINT MONO (290 1610);
FORCEPROP 0 LASTPIN (300 1550) $PN BY28
J 2
(290 1560);
DISPLAY 0.680851 (290 1560);
PAINT MONO (290 1560);
FORCEPROP 0 LASTPIN (300 2350) $PN CD28
J 2
(290 2360);
DISPLAY 0.680851 (290 2360);
PAINT MONO (290 2360);
FORCEPROP 0 LASTPIN (2700 1600) $PN BF67
J 0
(2710 1610);
DISPLAY 0.680851 (2710 1610);
PAINT MONO (2710 1610);
FORCEPROP 0 LASTPIN (2700 1550) $PN BK67
J 0
(2710 1560);
DISPLAY 0.680851 (2710 1560);
PAINT MONO (2710 1560);
FORCEPROP 0 LASTPIN (300 2300) $PN CC27
J 2
(290 2310);
DISPLAY 0.680851 (290 2310);
PAINT MONO (290 2310);
FORCEPROP 0 LASTPIN (300 2250) $PN BY30
J 2
(290 2260);
DISPLAY 0.680851 (290 2260);
PAINT MONO (290 2260);
FORCEPROP 0 LASTPIN (300 2200) $PN CA29
J 2
(290 2210);
DISPLAY 0.680851 (290 2210);
PAINT MONO (290 2210);
FORCEPROP 0 LASTPIN (300 2150) $PN BV30
J 2
(290 2160);
DISPLAY 0.680851 (290 2160);
PAINT MONO (290 2160);
FORCEPROP 0 LASTPIN (300 2100) $PN CA27
J 2
(290 2110);
DISPLAY 0.680851 (290 2110);
PAINT MONO (290 2110);
FORCEPROP 0 LASTPIN (300 2050) $PN BV28
J 2
(290 2060);
DISPLAY 0.680851 (290 2060);
PAINT MONO (290 2060);
FORCEPROP 0 LASTPIN (300 2000) $PN BU27
J 2
(290 2010);
DISPLAY 0.680851 (290 2010);
PAINT MONO (290 2010);
FORCEPROP 0 LASTPIN (300 1950) $PN BT28
J 2
(290 1960);
DISPLAY 0.680851 (290 1960);
PAINT MONO (290 1960);
FORCEPROP 0 LASTPIN (300 1900) $PN BU29
J 2
(290 1910);
DISPLAY 0.680851 (290 1910);
PAINT MONO (290 1910);
FORCEPROP 0 LASTPIN (2700 2400) $PN BC70
J 0
(2710 2410);
DISPLAY 0.680851 (2710 2410);
PAINT MONO (2710 2410);
FORCEPROP 0 LASTPIN (300 1850) $PN BT30
J 2
(290 1860);
DISPLAY 0.680851 (290 1860);
PAINT MONO (290 1860);
FORCEPROP 0 LASTPIN (2700 2350) $PN BE70
J 0
(2710 2360);
DISPLAY 0.680851 (2710 2360);
PAINT MONO (2710 2360);
FORCEPROP 0 LASTPIN (300 1800) $PN BN27
J 2
(290 1810);
DISPLAY 0.680851 (290 1810);
PAINT MONO (290 1810);
FORCEPROP 0 LASTPIN (2700 2300) $PN BD69
J 0
(2710 2310);
DISPLAY 0.680851 (2710 2310);
PAINT MONO (2710 2310);
FORCEPROP 0 LASTPIN (300 1750) $PN BP28
J 2
(290 1760);
DISPLAY 0.680851 (290 1760);
PAINT MONO (290 1760);
FORCEPROP 0 LASTPIN (2700 2250) $PN BF69
J 0
(2710 2260);
DISPLAY 0.680851 (2710 2260);
PAINT MONO (2710 2260);
FORCEPROP 0 LASTPIN (300 1700) $PN BN29
J 2
(290 1710);
DISPLAY 0.680851 (290 1710);
PAINT MONO (290 1710);
FORCEPROP 0 LASTPIN (2700 2200) $PN BH69
J 0
(2710 2210);
DISPLAY 0.680851 (2710 2210);
PAINT MONO (2710 2210);
FORCEPROP 0 LASTPIN (300 1650) $PN BP30
J 2
(290 1660);
DISPLAY 0.680851 (290 1660);
PAINT MONO (290 1660);
FORCEPROP 0 LASTPIN (2700 2150) $PN BC68
J 0
(2710 2160);
DISPLAY 0.680851 (2710 2160);
PAINT MONO (2710 2160);
FORCEPROP 0 LASTPIN (2700 2100) $PN BG68
J 0
(2710 2110);
DISPLAY 0.680851 (2710 2110);
PAINT MONO (2710 2110);
FORCEPROP 0 LASTPIN (2700 2050) $PN BD67
J 0
(2710 2060);
DISPLAY 0.680851 (2710 2060);
PAINT MONO (2710 2060);
FORCEPROP 0 LASTPIN (2700 2000) $PN BK69
J 0
(2710 2010);
DISPLAY 0.680851 (2710 2010);
PAINT MONO (2710 2010);
FORCEPROP 0 LASTPIN (2700 1950) $PN BM69
J 0
(2710 1960);
DISPLAY 0.680851 (2710 1960);
PAINT MONO (2710 1960);
FORCEPROP 0 LASTPIN (2700 1900) $PN BN68
J 0
(2710 1910);
DISPLAY 0.680851 (2710 1910);
PAINT MONO (2710 1910);
FORCEPROP 0 LASTPIN (2700 1850) $PN BG66
J 0
(2710 1860);
DISPLAY 0.680851 (2710 1860);
PAINT MONO (2710 1860);
FORCEPROP 0 LASTPIN (2700 1800) $PN BJ66
J 0
(2710 1810);
DISPLAY 0.680851 (2710 1810);
PAINT MONO (2710 1810);
FORCEPROP 0 LASTPIN (2700 1750) $PN BL66
J 0
(2710 1760);
DISPLAY 0.680851 (2710 1760);
PAINT MONO (2710 1760);
FORCEPROP 0 LASTPIN (2700 1700) $PN BM67
J 0
(2710 1710);
DISPLAY 0.680851 (2710 1710);
PAINT MONO (2710 1710);
FORCEPROP 0 LASTPIN (2700 1650) $PN BN66
J 0
(2710 1660);
DISPLAY 0.680851 (2710 1660);
PAINT MONO (2710 1660);
FORCEPROP 0 LASTPIN (300 2700) $PN BA23
J 2
(290 2710);
DISPLAY 0.680851 (290 2710);
PAINT MONO (290 2710);
FORCEPROP 0 LASTPIN (300 2650) $PN CW19
J 2
(290 2660);
DISPLAY 0.680851 (290 2660);
PAINT MONO (290 2660);
FORCEPROP 0 LASTPIN (300 2600) $PN BB65
J 2
(290 2610);
DISPLAY 0.680851 (290 2610);
PAINT MONO (290 2610);
FORCEPROP 0 LASTPIN (300 2550) $PN CK71
J 2
(290 2560);
DISPLAY 0.680851 (290 2560);
PAINT MONO (290 2560);
FORCEPROP 0 LASTPIN (300 3700) $PN AN17
J 2
(290 3710);
DISPLAY 0.680851 (290 3710);
PAINT MONO (290 3710);
FORCEPROP 0 LASTPIN (300 3650) $PN AR17
J 2
(290 3660);
DISPLAY 0.680851 (290 3660);
PAINT MONO (290 3660);
FORCEPROP 0 LASTPIN (300 3250) $PN AT67
J 2
(290 3260);
DISPLAY 0.680851 (290 3260);
PAINT MONO (290 3260);
FORCEPROP 0 LASTPIN (2700 2850) $PN AU66
J 0
(2710 2860);
DISPLAY 0.680851 (2710 2860);
PAINT MONO (2710 2860);
FORCEPROP 0 LASTPIN (300 3300) $PN AU68
J 2
(290 3310);
DISPLAY 0.680851 (290 3310);
PAINT MONO (290 3310);
FORCEPROP 0 LASTPIN (2700 2900) $PN AV67
J 0
(2710 2910);
DISPLAY 0.680851 (2710 2910);
PAINT MONO (2710 2910);
FORCEPROP 0 LASTPIN (2700 3650) $PN BL21
J 0
(2710 3660);
DISPLAY 0.680851 (2710 3660);
PAINT MONO (2710 3660);
FORCEPROP 0 LASTPIN (2700 3700) $PN BN21
J 0
(2710 3710);
DISPLAY 0.680851 (2710 3710);
PAINT MONO (2710 3710);
FORCEPROP 0 LASTPIN (300 3500) $PN BV22
J 2
(290 3510);
DISPLAY 0.680851 (290 3510);
PAINT MONO (290 3510);
FORCEPROP 0 LASTPIN (300 2850) $PN BW21
J 2
(290 2860);
DISPLAY 0.680851 (290 2860);
PAINT MONO (290 2860);
FORCEPROP 0 LASTPIN (2700 3250) $PN BW23
J 0
(2710 3260);
DISPLAY 0.680851 (2710 3260);
PAINT MONO (2710 3260);
FORCEPROP 0 LASTPIN (300 2900) $PN CA21
J 2
(290 2910);
DISPLAY 0.680851 (290 2910);
PAINT MONO (290 2910);
FORCEPROP 0 LASTPIN (300 3450) $PN CA23
J 2
(290 3460);
DISPLAY 0.680851 (290 3460);
PAINT MONO (290 3460);
FORCEPROP 0 LASTPIN (2700 3450) $PN CC21
J 0
(2710 3460);
DISPLAY 0.680851 (2710 3460);
PAINT MONO (2710 3460);
FORCEPROP 0 LASTPIN (2700 3300) $PN CC23
J 0
(2710 3310);
DISPLAY 0.680851 (2710 3310);
PAINT MONO (2710 3310);
FORCEPROP 0 LASTPIN (2700 3500) $PN CE21
J 0
(2710 3510);
DISPLAY 0.680851 (2710 3510);
PAINT MONO (2710 3510);
FORCEPROP 0 LASTPIN (2700 3100) $PN CL68
J 0
(2710 3110);
DISPLAY 0.680851 (2710 3110);
PAINT MONO (2710 3110);
FORCEPROP 0 LASTPIN (2700 3050) $PN CM69
J 0
(2710 3060);
DISPLAY 0.680851 (2710 3060);
PAINT MONO (2710 3060);
FORCEPROP 0 LASTPIN (300 3100) $PN CP69
J 2
(290 3110);
DISPLAY 0.680851 (290 3110);
PAINT MONO (290 3110);
FORCEPROP 0 LASTPIN (300 3050) $PN CR68
J 2
(290 3060);
DISPLAY 0.680851 (290 3060);
PAINT MONO (290 3060);
FORCEPROP 2 LAST CDS_LIB pure_quanta
J 0
(1500 2625);
DISPLAY INVISIBLE (1500 2625);
FORCEPROP 1 LAST NEEDS_NO_SIZE TRUE
J 0
(1500 2625);
DISPLAY 0.723404 (1500 2625);
PAINT GREEN (1500 2625);
DISPLAY INVISIBLE (1500 2625);
FORCEPROP 1 LAST CDS_LMAN_SYM_OUTLINE -1050,1250,1050,-1200
J 0
(1500 2625);
DISPLAY 0.468085 (1500 2625);
PAINT GREEN (1500 2625);
DISPLAY INVISIBLE (1500 2625);
FORCEPROP 2 LAST CDS_LOCATION U2
J 0
(450 4200);
DISPLAY 1.021277 (450 4200);
DISPLAY INVISIBLE (450 4200);
FORCEPROP 0 LAST $SEC 7
J 0
(450 4200);
DISPLAY 0.680851 (450 4200);
PAINT MONO (450 4200);
DISPLAY INVISIBLE (450 4200);
FORCEPROP 0 LAST CDS_SEC 7
J 0
(450 4200);
DISPLAY 1.021277 (450 4200);
DISPLAY INVISIBLE (450 4200);
FORCEPROP 1 LAST PATH I1
J 0
(1500 2625);
DISPLAY 0.723404 (1500 2625);
PAINT GREEN (1500 2625);
DISPLAY INVISIBLE (1500 2625);
FORCEADD OFFPAGE..1
(-1425 2700);
FORCEPROP 2 LAST $XR0 126 
J 0
(-1677 2700);
DISPLAY 0.638298 (-1677 2700);
PAINT MONO (-1677 2700);
FORCEPROP 2 LAST CDS_LIB standard
J 0
(-1425 2700);
PAINT MONO (-1425 2700);
DISPLAY INVISIBLE (-1425 2700);
FORCEPROP 1 LAST OFFPAGE TRUE
J 0
(-1100 2575);
DISPLAY 0.872340 (-1100 2575);
DISPLAY INVISIBLE (-1100 2575);
FORCEPROP 1 LAST COMMENT_BODY TRUE
J 0
(-1300 2600);
DISPLAY 0.872340 (-1300 2600);
PAINT GREEN (-1300 2600);
DISPLAY INVISIBLE (-1300 2600);
FORCEPROP 2 LAST PATH I2
J 0
(-1375 2775);
DISPLAY 1.021277 (-1375 2775);
DISPLAY INVISIBLE (-1375 2775);
FORCEADD OFFPAGE..1
(-1425 2650);
FORCEPROP 2 LAST $XR0 126 
J 0
(-1677 2650);
DISPLAY 0.638298 (-1677 2650);
PAINT MONO (-1677 2650);
FORCEPROP 2 LAST CDS_LIB standard
J 0
(-1425 2650);
PAINT MONO (-1425 2650);
DISPLAY INVISIBLE (-1425 2650);
FORCEPROP 1 LAST OFFPAGE TRUE
J 0
(-1100 2525);
DISPLAY 0.872340 (-1100 2525);
DISPLAY INVISIBLE (-1100 2525);
FORCEPROP 1 LAST COMMENT_BODY TRUE
J 0
(-1300 2550);
DISPLAY 0.872340 (-1300 2550);
PAINT GREEN (-1300 2550);
DISPLAY INVISIBLE (-1300 2550);
FORCEPROP 2 LAST PATH I3
J 0
(-1375 2725);
DISPLAY 1.021277 (-1375 2725);
DISPLAY INVISIBLE (-1375 2725);
FORCEADD OFFPAGE..1
(-1425 2600);
FORCEPROP 2 LAST $XR0 126 
J 0
(-1677 2600);
DISPLAY 0.638298 (-1677 2600);
PAINT MONO (-1677 2600);
FORCEPROP 2 LAST CDS_LIB standard
J 0
(-1425 2600);
PAINT MONO (-1425 2600);
DISPLAY INVISIBLE (-1425 2600);
FORCEPROP 1 LAST OFFPAGE TRUE
J 0
(-1100 2475);
DISPLAY 0.872340 (-1100 2475);
DISPLAY INVISIBLE (-1100 2475);
FORCEPROP 1 LAST COMMENT_BODY TRUE
J 0
(-1300 2500);
DISPLAY 0.872340 (-1300 2500);
PAINT GREEN (-1300 2500);
DISPLAY INVISIBLE (-1300 2500);
FORCEPROP 2 LAST PATH I4
J 0
(-1375 2675);
DISPLAY 1.021277 (-1375 2675);
DISPLAY INVISIBLE (-1375 2675);
FORCEADD OFFPAGE..1
(-1425 2550);
FORCEPROP 2 LAST $XR0 126 
J 0
(-1677 2550);
DISPLAY 0.638298 (-1677 2550);
PAINT MONO (-1677 2550);
FORCEPROP 2 LAST CDS_LIB standard
J 0
(-1425 2550);
PAINT MONO (-1425 2550);
DISPLAY INVISIBLE (-1425 2550);
FORCEPROP 1 LAST OFFPAGE TRUE
J 0
(-1100 2425);
DISPLAY 0.872340 (-1100 2425);
DISPLAY INVISIBLE (-1100 2425);
FORCEPROP 1 LAST COMMENT_BODY TRUE
J 0
(-1300 2450);
DISPLAY 0.872340 (-1300 2450);
PAINT GREEN (-1300 2450);
DISPLAY INVISIBLE (-1300 2450);
FORCEPROP 2 LAST PATH I5
J 0
(-1375 2625);
DISPLAY 1.021277 (-1375 2625);
DISPLAY INVISIBLE (-1375 2625);
FORCEADD QUANTA_TITLE_BLOCK_C..1
(6225 -1325);
FORCEPROP 0 LAST CDS_CON_LAST_MODIFIED Fri Aug 25 14:00:05 2023
J 0
(4340 -1310);
PAINT MONO (4340 -1310);
DISPLAY INVISIBLE (4340 -1310);
FORCEPROP 1 LAST CUSTOM_TXT_CDS <CON_LAST_MODIFIED>
J 0
(4340 -1310);
DISPLAY 0.978723 (4340 -1310);
FORCEPROP 2 LAST CUSTOM_TXT_CDS <XR_PAGE_TITLE>
J 0
(-1665 3925);
DISPLAY 0.638298 (-1665 3925);
PAINT PINK (-1665 3925);
DISPLAY INVISIBLE (-1665 3925);
FORCEPROP 2 LAST CUSTOM_TXT_CDS <Q_NUMBER>
J 0
(4822 -1222);
DISPLAY 1.212766 (4822 -1222);
FORCEPROP 1 LAST CUSTOM_TXT_CDS <NAME_2>
J 0
(3050 -1275);
FORCEPROP 1 LAST CUSTOM_TXT_CDS <NAME_1>
J 0
(3050 -1150);
FORCEPROP 1 LAST CUSTOM_TXT_CDS <Q_PROJ>
J 0
(3843 -1223);
DISPLAY 1.212766 (3843 -1223);
FORCEPROP 1 LAST CUSTOM_TXT_CDS <Q_REV>
J 0
(6041 -1222);
DISPLAY 1.212766 (6041 -1222);
FORCEPROP 1 LAST CUSTOM_TXT_CDS <CON_PAGE_NUM> OF <CON_TOTAL_PAGES>
J 0
(5779 -1307);
DISPLAY 0.978723 (5779 -1307);
FORCEPROP 1 LAST Q_TITLE SPR CPU0 MISC:7 OF 30)
J 0
(-3141 -1299);
DISPLAY 1.957447 (-3141 -1299);
PAINT GREEN (-3141 -1299);
FORCEPROP 1 LAST Q_DEPT 
J 1
(2462 -1276);
DISPLAY 1.957447 (2462 -1276);
PAINT GREEN (2462 -1276);
FORCEPROP 2 LAST CDS_LIB pure_quanta
J 0
(6225 -1325);
PAINT MONO (6225 -1325);
DISPLAY INVISIBLE (6225 -1325);
FORCEPROP 1 LAST CDS_LMAN_SYM_OUTLINE -9475,6775,100,-125
J 0
(6225 -1325);
DISPLAY 0.468085 (6225 -1325);
PAINT GREEN (6225 -1325);
DISPLAY INVISIBLE (6225 -1325);
FORCEPROP 2 LAST PAGE_BORDER TRUE
J 0
(-1665 3925);
DISPLAY 0.638298 (-1665 3925);
PAINT PINK (-1665 3925);
DISPLAY INVISIBLE (-1665 3925);
FORCEPROP 2 LAST CDS_XR_PAGE_TITLE CR-19 : @S9S_MB_2U_LIB.S9S_MB_2U(SCH_1):PAGE19
J 0
(-1665 3925);
DISPLAY 0.638298 (-1665 3925);
PAINT PINK (-1665 3925);
DISPLAY INVISIBLE (-1665 3925);
FORCEPROP 1 LAST COMMENT_BODY TRUE
J 0
(6237 -1338);
DISPLAY 0.978723 (6237 -1338);
PAINT GREEN (6237 -1338);
DISPLAY INVISIBLE (6237 -1338);
WIRE 16 -1 (-1375 2650)(300 2650);
FORCEPROP 2 LAST SIG_NAME PU_CPU0_UPI1_AC_COUPLING
J 0
(-1312 2659);
DISPLAY 0.680851 (-1312 2659);
PAINT WHITE (-1312 2659);
WIRE 16 -1 (300 2700)(-1375 2700);
FORCEPROP 2 LAST SIG_NAME PU_CPU0_UPI0_AC_COUPLING
J 0
(-1312 2709);
DISPLAY 0.680851 (-1312 2709);
PAINT WHITE (-1312 2709);
WIRE 16 -1 (300 2850)(-1375 2850);
FORCEPROP 2 LAST SIG_NAME NC_CPU0_DMI_APROBE<1>
J 0
(-1312 2859);
DISPLAY 0.680851 (-1312 2859);
PAINT WHITE (-1312 2859);
WIRE 16 -1 (-1375 2900)(300 2900);
FORCEPROP 2 LAST SIG_NAME NC_CPU0_DMI_APROBE<0>
J 0
(-1312 2909);
DISPLAY 0.680851 (-1312 2909);
PAINT WHITE (-1312 2909);
WIRE 16 -1 (-1375 3050)(300 3050);
FORCEPROP 2 LAST SIG_NAME NC_CPU0_UPI3_APROBE<1>
J 0
(-1312 3059);
DISPLAY 0.680851 (-1312 3059);
PAINT WHITE (-1312 3059);
WIRE 16 -1 (-1375 3100)(300 3100);
FORCEPROP 2 LAST SIG_NAME NC_CPU0_UPI3_APROBE<0>
J 0
(-1312 3109);
DISPLAY 0.680851 (-1312 3109);
PAINT WHITE (-1312 3109);
WIRE 16 -1 (-1375 3250)(300 3250);
FORCEPROP 2 LAST SIG_NAME NC_CPU0_UPI2_APROBE<1>
J 0
(-1312 3259);
DISPLAY 0.680851 (-1312 3259);
PAINT WHITE (-1312 3259);
WIRE 16 -1 (300 3300)(-1375 3300);
FORCEPROP 2 LAST SIG_NAME NC_CPU0_UPI2_APROBE<0>
J 0
(-1312 3309);
DISPLAY 0.680851 (-1312 3309);
PAINT WHITE (-1312 3309);
WIRE 16 -1 (300 3650)(-1375 3650);
FORCEPROP 2 LAST SIG_NAME NC_CPU0_UPI0_APROBE<1>
J 0
(-1312 3659);
DISPLAY 0.680851 (-1312 3659);
PAINT WHITE (-1312 3659);
WIRE 16 -1 (300 3700)(-1375 3700);
FORCEPROP 2 LAST SIG_NAME NC_CPU0_UPI0_APROBE<0>
J 0
(-1312 3709);
DISPLAY 0.680851 (-1312 3709);
PAINT WHITE (-1312 3709);
WIRE 16 -1 (-1375 1650)(300 1650);
FORCEPROP 2 LAST SIG_NAME TP_TRC_CPU0_PTI<15>
J 0
(-1312 1659);
DISPLAY 0.680851 (-1312 1659);
PAINT WHITE (-1312 1659);
WIRE 16 -1 (-1375 1700)(300 1700);
FORCEPROP 2 LAST SIG_NAME TP_TRC_CPU0_PTI<14>
J 0
(-1312 1709);
DISPLAY 0.680851 (-1312 1709);
PAINT WHITE (-1312 1709);
WIRE 16 -1 (-1375 1750)(300 1750);
FORCEPROP 2 LAST SIG_NAME TP_TRC_CPU0_PTI<13>
J 0
(-1312 1759);
DISPLAY 0.680851 (-1312 1759);
PAINT WHITE (-1312 1759);
WIRE 16 -1 (-1375 1800)(300 1800);
FORCEPROP 2 LAST SIG_NAME TP_TRC_CPU0_PTI<12>
J 0
(-1312 1809);
DISPLAY 0.680851 (-1312 1809);
PAINT WHITE (-1312 1809);
WIRE 16 -1 (300 1850)(-1375 1850);
FORCEPROP 2 LAST SIG_NAME TP_TRC_CPU0_PTI<11>
J 0
(-1312 1859);
DISPLAY 0.680851 (-1312 1859);
PAINT WHITE (-1312 1859);
WIRE 16 -1 (-1375 1900)(300 1900);
FORCEPROP 2 LAST SIG_NAME TP_TRC_CPU0_PTI<10>
J 0
(-1312 1909);
DISPLAY 0.680851 (-1312 1909);
PAINT WHITE (-1312 1909);
WIRE 16 -1 (300 1950)(-1375 1950);
FORCEPROP 2 LAST SIG_NAME TP_TRC_CPU0_PTI<9>
J 0
(-1312 1959);
DISPLAY 0.680851 (-1312 1959);
PAINT WHITE (-1312 1959);
WIRE 16 -1 (-1375 2000)(300 2000);
FORCEPROP 2 LAST SIG_NAME TP_TRC_CPU0_PTI<8>
J 0
(-1312 2009);
DISPLAY 0.680851 (-1312 2009);
PAINT WHITE (-1312 2009);
WIRE 16 -1 (-1375 2050)(300 2050);
FORCEPROP 2 LAST SIG_NAME TP_TRC_CPU0_PTI<7>
J 0
(-1312 2059);
DISPLAY 0.680851 (-1312 2059);
PAINT WHITE (-1312 2059);
WIRE 16 -1 (-1375 2100)(300 2100);
FORCEPROP 2 LAST SIG_NAME TP_TRC_CPU0_PTI<6>
J 0
(-1312 2109);
DISPLAY 0.680851 (-1312 2109);
PAINT WHITE (-1312 2109);
WIRE 16 -1 (-1375 2150)(300 2150);
FORCEPROP 2 LAST SIG_NAME TP_TRC_CPU0_PTI<5>
J 0
(-1312 2159);
DISPLAY 0.680851 (-1312 2159);
PAINT WHITE (-1312 2159);
WIRE 16 -1 (-1375 2200)(300 2200);
FORCEPROP 2 LAST SIG_NAME TP_TRC_CPU0_PTI<4>
J 0
(-1312 2209);
DISPLAY 0.680851 (-1312 2209);
PAINT WHITE (-1312 2209);
WIRE 16 -1 (300 2250)(-1375 2250);
FORCEPROP 2 LAST SIG_NAME TP_TRC_CPU0_PTI<3>
J 0
(-1312 2259);
DISPLAY 0.680851 (-1312 2259);
PAINT WHITE (-1312 2259);
WIRE 16 -1 (-1375 2300)(300 2300);
FORCEPROP 2 LAST SIG_NAME TP_TRC_CPU0_PTI<2>
J 0
(-1312 2309);
DISPLAY 0.680851 (-1312 2309);
PAINT WHITE (-1312 2309);
WIRE 16 -1 (-1375 2350)(300 2350);
FORCEPROP 2 LAST SIG_NAME TP_TRC_CPU0_PTI_MON<1>
J 0
(-1312 2359);
DISPLAY 0.680851 (-1312 2359);
PAINT WHITE (-1312 2359);
WIRE 16 -1 (300 2400)(-1375 2400);
FORCEPROP 2 LAST SIG_NAME TP_TP_TRC_CPU0_PTI_MON<0>
J 0
(-1312 2409);
DISPLAY 0.680851 (-1312 2409);
PAINT WHITE (-1312 2409);
WIRE 16 -1 (-1375 1600)(300 1600);
FORCEPROP 2 LAST SIG_NAME TP_TRC_CPU0_PTI0_CLK
J 0
(-1312 1609);
DISPLAY 0.680851 (-1312 1609);
PAINT WHITE (-1312 1609);
WIRE 16 -1 (300 1550)(-1375 1550);
FORCEPROP 2 LAST SIG_NAME TP_TRC_CPU0_PTI1_CLK
J 0
(-1312 1559);
DISPLAY 0.680851 (-1312 1559);
PAINT WHITE (-1312 1559);
WIRE 16 -1 (4375 1650)(2700 1650);
FORCEPROP 2 LAST SIG_NAME TP_TRC_CPU0_PTI<31>
J 0
(2959 1659);
DISPLAY 0.680851 (2959 1659);
PAINT WHITE (2959 1659);
WIRE 16 -1 (4375 1700)(2700 1700);
FORCEPROP 2 LAST SIG_NAME TP_TRC_CPU0_PTI<30>
J 0
(2959 1709);
DISPLAY 0.680851 (2959 1709);
PAINT WHITE (2959 1709);
WIRE 16 -1 (4375 1750)(2700 1750);
FORCEPROP 2 LAST SIG_NAME TP_TRC_CPU0_PTI<29>
J 0
(2959 1759);
DISPLAY 0.680851 (2959 1759);
PAINT WHITE (2959 1759);
WIRE 16 -1 (4375 1800)(2700 1800);
FORCEPROP 2 LAST SIG_NAME TP_TRC_CPU0_PTI<28>
J 0
(2959 1809);
DISPLAY 0.680851 (2959 1809);
PAINT WHITE (2959 1809);
WIRE 16 -1 (4375 1850)(2700 1850);
FORCEPROP 2 LAST SIG_NAME TP_TRC_CPU0_PTI<27>
J 0
(2959 1859);
DISPLAY 0.680851 (2959 1859);
PAINT WHITE (2959 1859);
WIRE 16 -1 (4375 1900)(2700 1900);
FORCEPROP 2 LAST SIG_NAME TP_TRC_CPU0_PTI<26>
J 0
(2959 1909);
DISPLAY 0.680851 (2959 1909);
PAINT WHITE (2959 1909);
WIRE 16 -1 (4375 1950)(2700 1950);
FORCEPROP 2 LAST SIG_NAME TP_TRC_CPU0_PTI<25>
J 0
(2959 1959);
DISPLAY 0.680851 (2959 1959);
PAINT WHITE (2959 1959);
WIRE 16 -1 (4375 2000)(2700 2000);
FORCEPROP 2 LAST SIG_NAME TP_TRC_CPU0_PTI<24>
J 0
(2959 2009);
DISPLAY 0.680851 (2959 2009);
PAINT WHITE (2959 2009);
WIRE 16 -1 (4375 2050)(2700 2050);
FORCEPROP 2 LAST SIG_NAME TP_TRC_CPU0_PTI<23>
J 0
(2959 2059);
DISPLAY 0.680851 (2959 2059);
PAINT WHITE (2959 2059);
WIRE 16 -1 (4375 2100)(2700 2100);
FORCEPROP 2 LAST SIG_NAME TP_TRC_CPU0_PTI<22>
J 0
(2959 2109);
DISPLAY 0.680851 (2959 2109);
PAINT WHITE (2959 2109);
WIRE 16 -1 (4375 2150)(2700 2150);
FORCEPROP 2 LAST SIG_NAME TP_TRC_CPU0_PTI<21>
J 0
(2959 2159);
DISPLAY 0.680851 (2959 2159);
PAINT WHITE (2959 2159);
WIRE 16 -1 (4375 2200)(2700 2200);
FORCEPROP 2 LAST SIG_NAME TP_TRC_CPU0_PTI<20>
J 0
(2959 2209);
DISPLAY 0.680851 (2959 2209);
PAINT WHITE (2959 2209);
WIRE 16 -1 (4375 2250)(2700 2250);
FORCEPROP 2 LAST SIG_NAME TP_TRC_CPU0_PTI<19>
J 0
(2959 2259);
DISPLAY 0.680851 (2959 2259);
PAINT WHITE (2959 2259);
WIRE 16 -1 (4375 2300)(2700 2300);
FORCEPROP 2 LAST SIG_NAME TP_TRC_CPU0_PTI<18>
J 0
(2959 2309);
DISPLAY 0.680851 (2959 2309);
PAINT WHITE (2959 2309);
WIRE 16 -1 (4375 2350)(2700 2350);
FORCEPROP 2 LAST SIG_NAME TP_TRC_CPU0_PTI<17>
J 0
(2959 2359);
DISPLAY 0.680851 (2959 2359);
PAINT WHITE (2959 2359);
WIRE 16 -1 (4375 2400)(2700 2400);
FORCEPROP 2 LAST SIG_NAME TP_TRC_CPU0_PTI<16>
J 0
(2959 2409);
DISPLAY 0.680851 (2959 2409);
PAINT WHITE (2959 2409);
WIRE 16 -1 (4375 1600)(2700 1600);
FORCEPROP 2 LAST SIG_NAME TP_TRC_CPU0_PTI2_CLK
J 0
(2959 1609);
DISPLAY 0.680851 (2959 1609);
PAINT WHITE (2959 1609);
WIRE 16 -1 (4375 1550)(2700 1550);
FORCEPROP 2 LAST SIG_NAME TP_TRC_CPU0_PTI3_CLK
J 0
(2959 1559);
DISPLAY 0.680851 (2959 1559);
PAINT WHITE (2959 1559);
WIRE 16 -1 (4375 3100)(2700 3100);
FORCEPROP 2 LAST SIG_NAME NC_CPU0_PE3_APROBE<0>
J 0
(2959 3109);
DISPLAY 0.680851 (2959 3109);
PAINT WHITE (2959 3109);
WIRE 16 -1 (4375 3050)(2700 3050);
FORCEPROP 2 LAST SIG_NAME NC_CPU0_PE3_APROBE<1>
J 0
(2959 3059);
DISPLAY 0.680851 (2959 3059);
PAINT WHITE (2959 3059);
WIRE 16 -1 (4375 2850)(2700 2850);
FORCEPROP 2 LAST SIG_NAME NC_CPU0_PE4_APROBE<1>
J 0
(2959 2859);
DISPLAY 0.680851 (2959 2859);
PAINT WHITE (2959 2859);
WIRE 16 -1 (4375 2900)(2700 2900);
FORCEPROP 2 LAST SIG_NAME NC_CPU0_PE4_APROBE<0>
J 0
(2959 2909);
DISPLAY 0.680851 (2959 2909);
PAINT WHITE (2959 2909);
WIRE 16 -1 (4375 3650)(2700 3650);
FORCEPROP 2 LAST SIG_NAME NC_CPU0_PE0_APROBE<1>
J 0
(2959 3659);
DISPLAY 0.680851 (2959 3659);
PAINT WHITE (2959 3659);
WIRE 16 -1 (4375 3700)(2700 3700);
FORCEPROP 2 LAST SIG_NAME NC_CPU0_PE0_APROBE<0>
J 0
(2959 3709);
DISPLAY 0.680851 (2959 3709);
PAINT WHITE (2959 3709);
WIRE 16 -1 (-1375 3500)(300 3500);
FORCEPROP 2 LAST SIG_NAME NC_CPU0_UPI1_APROBE<0>
J 0
(-1312 3509);
DISPLAY 0.680851 (-1312 3509);
PAINT WHITE (-1312 3509);
WIRE 16 -1 (4375 3250)(2700 3250);
FORCEPROP 2 LAST SIG_NAME NC_CPU0_PE2_APROBE<1>
J 0
(2959 3259);
DISPLAY 0.680851 (2959 3259);
PAINT WHITE (2959 3259);
WIRE 16 -1 (300 3450)(-1375 3450);
FORCEPROP 2 LAST SIG_NAME NC_CPU0_UPI1_APROBE<1>
J 0
(-1312 3459);
DISPLAY 0.680851 (-1312 3459);
PAINT WHITE (-1312 3459);
WIRE 16 -1 (4375 3450)(2700 3450);
FORCEPROP 2 LAST SIG_NAME NC_CPU0_PE1_APROBE<1>
J 0
(2959 3459);
DISPLAY 0.680851 (2959 3459);
PAINT WHITE (2959 3459);
WIRE 16 -1 (4375 3300)(2700 3300);
FORCEPROP 2 LAST SIG_NAME NC_CPU0_PE2_APROBE<0>
J 0
(2959 3309);
DISPLAY 0.680851 (2959 3309);
PAINT WHITE (2959 3309);
WIRE 16 -1 (4375 3500)(2700 3500);
FORCEPROP 2 LAST SIG_NAME NC_CPU0_PE1_APROBE<0>
J 0
(2959 3509);
DISPLAY 0.680851 (2959 3509);
PAINT WHITE (2959 3509);
WIRE 16 -1 (-1375 2600)(300 2600);
FORCEPROP 2 LAST SIG_NAME PU_CPU0_UPI2_AC_COUPLING
J 0
(-1312 2609);
DISPLAY 0.680851 (-1312 2609);
PAINT WHITE (-1312 2609);
WIRE 16 -1 (300 2550)(-1375 2550);
FORCEPROP 2 LAST SIG_NAME PU_CPU0_UPI3_AC_COUPLING
J 0
(-1312 2559);
DISPLAY 0.680851 (-1312 2559);
PAINT WHITE (-1312 2559);
QUIT
